# BASEBOARD_FAB2 (Tioga Pass) — schematic netlist excerpt (pin names and nets, part order shuffled) for the footprints in the layout excerpt that follows; sources: Cadence DE-HDL packaged netlist, KiCad conversion of Wiwynn_Tioga_Pass_MB.brd

R7D4  RES  10.0K 1% CHIP  pkg 0402  page 133 : A = P3V3_STBY ; B = PU_IRQ_PCH_SCI_WHEA_N
C25W95  CAP_A  0.1UF 16V 10% X7R  pkg 0402V  page 254 : A = P3V3_STBY ; B = GND
C3N5  CAP_A  1.0UF 6.3V 10% X6S  pkg 0402V  page 132 : A = PVNN_PCH_STBY ; B = GND

(kicad_pcb
	(version 20260206)
	(generator "pcbnew")
	(generator_version "10.0")
	(general
		(thickness 1.6)
		(legacy_teardrops no)
	)
	(paper "A4")
	(title_block
		(title "Wiwynn_Tioga_Pass_MB.brd")
		(comment 1 "Tioga Pass / footprints 4748-4750 of 4770")
	)
	(layers
		(0 "F.Cu" signal "TOP")
		(4 "In1.Cu" signal "L2GND")
		(6 "In2.Cu" signal "L3")
		(8 "In3.Cu" signal "L4GND")
		(10 "In4.Cu" signal "L5")
		(12 "In5.Cu" signal "L6GND")
		(14 "In6.Cu" signal "L7VCC")
		(16 "In7.Cu" signal "L8VCC")
		(18 "In8.Cu" signal "L9GND")
		(20 "In9.Cu" signal "L10")
		(22 "In10.Cu" signal "L11GND")
		(24 "In11.Cu" signal "L12")
		(26 "In12.Cu" signal "L13GND")
		(2 "B.Cu" signal "BOTTOM")
		(9 "F.Adhes" user "F.Adhesive")
		(11 "B.Adhes" user "B.Adhesive")
		(13 "F.Paste" user "Package Geometry/Pastemask Top")
		(15 "B.Paste" user "Package Geometry/Pastemask Bottom")
		(5 "F.SilkS" user "Ref Des/Silkscreen Top")
		(7 "B.SilkS" user "Ref Des/Silkscreen Bottom")
		(1 "F.Mask" user "Board Geometry/Soldermask Top")
		(3 "B.Mask" user "Board Geometry/Soldermask Bottom")
		(17 "Dwgs.User" user "User.Drawings")
		(19 "Cmts.User" user "User.Comments")
		(21 "Eco1.User" user "User.Eco1")
		(23 "Eco2.User" user "User.Eco2")
		(25 "Edge.Cuts" user "Board Geometry/Outline")
		(27 "Margin" user)
		(31 "F.CrtYd" user "Package Geometry/Place Bound Top")
		(29 "B.CrtYd" user "Package Geometry/Place Bound Bottom")
		(35 "F.Fab" user "Ref Des/Assembly Top")
		(33 "B.Fab" user "Ref Des/Assembly Bottom")
	)
	(footprint ""
		(layer "B.Cu")
		(at 439.4073 -141.097 180)
		(property "Reference" "C25W95"
			(at 0.8382 -0.67818 180)
			(unlocked yes)
			(layer "B.SilkS")
			(effects
				(font
					(size 0.4064 0.254)
					(thickness 0.1524)
				)
				(justify left mirror)
			)
		)
		(property "Value" ""
			(at 0 0 0)
			(layer "B.Fab")
			(effects
				(font
					(size 1.27 1.27)
				)
				(justify mirror)
			)
		)
		(duplicate_pad_numbers_are_jumpers no)
		(fp_poly
			(pts
				(xy -0.3048 -0.1016) (xy -0.3048 0.9906) (xy 0.3048 0.9906) (xy 0.3048 -0.1016)
			)
			(stroke
				(width 0)
				(type default)
			)
			(fill no)
			(layer "B.CrtYd")
		)
		(fp_line
			(start 0.3048 0.9906)
			(end -0.3048 0.9906)
			(stroke
				(width 0.1)
				(type default)
			)
			(layer "B.Fab")
		)
		(fp_line
			(start 0.3048 -0.1016)
			(end 0.3048 0.9906)
			(stroke
				(width 0.1)
				(type default)
			)
			(layer "B.Fab")
		)
		(fp_line
			(start -0.3048 0.9906)
			(end -0.3048 -0.1016)
			(stroke
				(width 0.1)
				(type default)
			)
			(layer "B.Fab")
		)
		(fp_line
			(start -0.3048 -0.1016)
			(end 0.3048 -0.1016)
			(stroke
				(width 0.1)
				(type default)
			)
			(layer "B.Fab")
		)
		(pad "1" smd rect
			(at 0 0)
			(size 0.508 0.508)
			(layers "B.Cu" "B.Mask" "B.Paste")
			(net "P3V3_STBY")
		)
		(pad "2" smd rect
			(at 0 0.889)
			(size 0.508 0.508)
			(layers "B.Cu" "B.Mask" "B.Paste")
			(net "GND")
		)
		(zone
			(layer "B.Cu")
			(hatch none 0.5)
			(connect_pads
				(clearance 0)
			)
			(min_thickness 0.25)
			(keepout
				(tracks not_allowed)
				(vias allowed)
				(pads allowed)
				(copperpour not_allowed)
				(footprints allowed)
			)
			(placement
				(enabled no)
				(sheetname "")
			)
			(fill
				(thermal_gap 0.5)
				(thermal_bridge_width 0.5)
				(island_removal_mode 0)
			)
			(polygon
				(pts
					(xy 439.1533 -141.732) (xy 439.6613 -141.732) (xy 439.6613 -141.351) (xy 439.1533 -141.351)
				)
			)
		)
		(zone
			(layer "B.Cu")
			(hatch none 0.5)
			(connect_pads
				(clearance 0)
			)
			(min_thickness 0.25)
			(keepout
				(tracks allowed)
				(vias not_allowed)
				(pads allowed)
				(copperpour not_allowed)
				(footprints allowed)
			)
			(placement
				(enabled no)
				(sheetname "")
			)
			(fill
				(thermal_gap 0.5)
				(thermal_bridge_width 0.5)
				(island_removal_mode 0)
			)
			(polygon
				(pts
					(xy 439.1533 -141.351) (xy 439.6613 -141.351) (xy 439.6613 -141.732) (xy 439.1533 -141.732)
				)
			)
		)
	)
	(footprint ""
		(layer "B.Cu")
		(at 386.93725 -111.05515 180)
		(property "Reference" "C3N5"
			(at 0 0 0)
			(layer "B.SilkS")
			(hide yes)
			(effects
				(font
					(size 1.27 1.27)
				)
				(justify mirror)
			)
		)
		(property "Value" ""
			(at 0 0 0)
			(layer "B.Fab")
			(effects
				(font
					(size 1.27 1.27)
				)
				(justify mirror)
			)
		)
		(duplicate_pad_numbers_are_jumpers no)
		(fp_rect
			(start 0.2794 0.9144)
			(end -0.2794 -0.1143)
			(stroke
				(width 0)
				(type default)
			)
			(fill no)
			(layer "B.CrtYd")
		)
		(fp_line
			(start 0.2794 0.9144)
			(end 0.2794 -0.1143)
			(stroke
				(width 0.1)
				(type default)
			)
			(layer "B.Fab")
		)
		(fp_line
			(start 0.2794 -0.1143)
			(end -0.2794 -0.1143)
			(stroke
				(width 0.1)
				(type default)
			)
			(layer "B.Fab")
		)
		(fp_line
			(start -0.2794 0.9144)
			(end 0.2794 0.9144)
			(stroke
				(width 0.1)
				(type default)
			)
			(layer "B.Fab")
		)
		(fp_line
			(start -0.2794 -0.1143)
			(end -0.2794 0.9144)
			(stroke
				(width 0.1)
				(type default)
			)
			(layer "B.Fab")
		)
		(pad "1" smd custom
			(at 0 0 90)
			(size 0.10414 0.10414)
			(layers "B.Cu" "B.Mask" "B.Paste")
			(net "PVNN_PCH_STBY")
			(options
				(clearance outline)
				(anchor circle)
			)
			(primitives
				(gr_poly
					(pts
						(xy -0.20828 -0.08636) (xy -0.20828 0.08636) (xy -0.08636 0.20828) (xy 0.086614 0.20828) (xy 0.20828 0.086614)
						(xy 0.20828 -0.08636) (xy 0.08636 -0.20828) (xy -0.08636 -0.20828)
					)
					(width 0)
					(fill yes)
				)
			)
		)
		(pad "2" smd custom
			(at 0 0.8001 90)
			(size 0.10414 0.10414)
			(layers "B.Cu" "B.Mask" "B.Paste")
			(net "GND")
			(options
				(clearance outline)
				(anchor circle)
			)
			(primitives
				(gr_poly
					(pts
						(xy -0.20828 -0.08636) (xy -0.20828 0.08636) (xy -0.08636 0.20828) (xy 0.086614 0.20828) (xy 0.20828 0.086614)
						(xy 0.20828 -0.08636) (xy 0.08636 -0.20828) (xy -0.08636 -0.20828)
					)
					(width 0)
					(fill yes)
				)
			)
		)
		(zone
			(layer "B.Cu")
			(hatch none 0.5)
			(connect_pads
				(clearance 0)
			)
			(min_thickness 0.25)
			(keepout
				(tracks allowed)
				(vias not_allowed)
				(pads allowed)
				(copperpour not_allowed)
				(footprints allowed)
			)
			(placement
				(enabled no)
				(sheetname "")
			)
			(fill
				(thermal_gap 0.5)
				(thermal_bridge_width 0.5)
				(island_removal_mode 0)
			)
			(polygon
				(pts
					(xy 386.84962 -111.2647) (xy 386.84962 -111.6457) (xy 387.02488 -111.6457) (xy 387.025134 -111.2647)
				)
			)
		)
		(zone
			(layer "B.Cu")
			(hatch none 0.5)
			(connect_pads
				(clearance 0)
			)
			(min_thickness 0.25)
			(keepout
				(tracks not_allowed)
				(vias allowed)
				(pads allowed)
				(copperpour not_allowed)
				(footprints allowed)
			)
			(placement
				(enabled no)
				(sheetname "")
			)
			(fill
				(thermal_gap 0.5)
				(thermal_bridge_width 0.5)
				(island_removal_mode 0)
			)
			(polygon
				(pts
					(xy 386.84962 -111.2647) (xy 386.84962 -111.6457) (xy 387.02488 -111.6457) (xy 387.025134 -111.2647)
				)
			)
		)
	)
	(footprint ""
		(layer "B.Cu")
		(at 381.508 -87.3125 180)
		(property "Reference" "R7D4"
			(at 0 0 0)
			(layer "B.SilkS")
			(hide yes)
			(effects
				(font
					(size 1.27 1.27)
				)
				(justify mirror)
			)
		)
		(property "Value" ""
			(at 0 0 0)
			(layer "B.Fab")
			(effects
				(font
					(size 1.27 1.27)
				)
				(justify mirror)
			)
		)
		(duplicate_pad_numbers_are_jumpers no)
		(fp_poly
			(pts
				(xy 0.2794 -0.1016) (xy -0.2794 -0.1016) (xy -0.2794 0.9906) (xy 0.2794 0.9906)
			)
			(stroke
				(width 0)
				(type default)
			)
			(fill no)
			(layer "B.CrtYd")
		)
		(fp_line
			(start 0.2794 0.9906)
			(end -0.2794 0.9906)
			(stroke
				(width 0.1)
				(type default)
			)
			(layer "B.Fab")
		)
		(fp_line
			(start 0.2794 -0.1016)
			(end 0.2794 0.9906)
			(stroke
				(width 0.1)
				(type default)
			)
			(layer "B.Fab")
		)
		(fp_line
			(start -0.2794 0.9906)
			(end -0.2794 -0.1016)
			(stroke
				(width 0.1)
				(type default)
			)
			(layer "B.Fab")
		)
		(fp_line
			(start -0.2794 -0.1016)
			(end 0.2794 -0.1016)
			(stroke
				(width 0.1)
				(type default)
			)
			(layer "B.Fab")
		)
		(pad "1" smd rect
			(at 0 0)
			(size 0.508 0.508)
			(layers "B.Cu" "B.Mask" "B.Paste")
			(net "P3V3_STBY")
		)
		(pad "2" smd rect
			(at 0 0.889)
			(size 0.508 0.508)
			(layers "B.Cu" "B.Mask" "B.Paste")
			(net "PU_IRQ_PCH_SCI_WHEA_N")
		)
		(zone
			(layer "B.Cu")
			(hatch none 0.5)
			(connect_pads
				(clearance 0)
			)
			(min_thickness 0.25)
			(keepout
				(tracks not_allowed)
				(vias allowed)
				(pads allowed)
				(copperpour not_allowed)
				(footprints allowed)
			)
			(placement
				(enabled no)
				(sheetname "")
			)
			(fill
				(thermal_gap 0.5)
				(thermal_bridge_width 0.5)
				(island_removal_mode 0)
			)
			(polygon
				(pts
					(xy 381.254 -87.9475) (xy 381.762 -87.9475) (xy 381.762 -87.5665) (xy 381.254 -87.5665)
				)
			)
		)
		(zone
			(layer "B.Cu")
			(hatch none 0.5)
			(connect_pads
				(clearance 0)
			)
			(min_thickness 0.25)
			(keepout
				(tracks allowed)
				(vias not_allowed)
				(pads allowed)
				(copperpour not_allowed)
				(footprints allowed)
			)
			(placement
				(enabled no)
				(sheetname "")
			)
			(fill
				(thermal_gap 0.5)
				(thermal_bridge_width 0.5)
				(island_removal_mode 0)
			)
			(polygon
				(pts
					(xy 381.254 -87.5665) (xy 381.762 -87.5665) (xy 381.762 -87.9475) (xy 381.254 -87.9475)
				)
			)
		)
	)
)
